#ISCELL
  pure_quanta quanta_title_block_c *
  *
#CELL
  pure_quanta socket4677_azif0045p001c01cs *
  page15_i1
#ISCELL
  standard offpage *
  page15_i10
#ISCELL
  standard offpage *
  page15_i11
#ISCELL
  standard offpage *
  page15_i13
#ISCELL
  standard offpage *
  page15_i14
#ISCELL
  standard offpage *
  page15_i15
#ISCELL
  standard offpage *
  page15_i25
#ISCELL
  standard offpage *
  page15_i3
#ISCELL
  standard offpage *
  page15_i31
#ISCELL
  standard offpage *
  page15_i4
#ISCELL
  standard offpage *
  page15_i5
#ISCELL
  standard offpage *
  page15_i6
#ISCELL
  standard offpage *
  page15_i7
#ISCELL
  standard offpage *
  page15_i8
#ISCELL
  standard offpage *
  page15_i9
